(kicad_pcb
	(version 20260206)
	(generator "pcbnew")
	(generator_version "10.0")
	(general
		(thickness 1.6)
		(legacy_teardrops no)
	)
	(paper "A4")
	(title_block
		(title "Bryce Canyon_IOM_M2_16342-2_OCP.brd")
		(comment 1 "Bryce Canyon / footprints 571-576 of 1146")
	)
	(layers
		(0 "F.Cu" signal "TOP")
		(4 "In1.Cu" signal "L2GND")
		(6 "In2.Cu" signal "L3")
		(8 "In3.Cu" signal "L4VCC")
		(10 "In4.Cu" signal "L5VCC")
		(12 "In5.Cu" signal "L6")
		(14 "In6.Cu" signal "L7GND")
		(2 "B.Cu" signal "BOTTOM")
		(9 "F.Adhes" user "F.Adhesive")
		(11 "B.Adhes" user "B.Adhesive")
		(13 "F.Paste" user "Package Geometry/Pastemask Top")
		(15 "B.Paste" user "Package Geometry/Pastemask Bottom")
		(5 "F.SilkS" user "Ref Des/Silkscreen Top")
		(7 "B.SilkS" user "Ref Des/Silkscreen Bottom")
		(1 "F.Mask" user "Board Geometry/Soldermask Top")
		(3 "B.Mask" user "Board Geometry/Soldermask Bottom")
		(17 "Dwgs.User" user "User.Drawings")
		(19 "Cmts.User" user "User.Comments")
		(21 "Eco1.User" user "User.Eco1")
		(23 "Eco2.User" user "User.Eco2")
		(25 "Edge.Cuts" user "Board Geometry/Outline")
		(27 "Margin" user)
		(31 "F.CrtYd" user "Package Geometry/Place Bound Top")
		(29 "B.CrtYd" user "Package Geometry/Place Bound Bottom")
		(35 "F.Fab" user "Ref Des/Assembly Top")
		(33 "B.Fab" user "Ref Des/Assembly Bottom")
	)
	(footprint ""
		(layer "F.Cu")
		(at 63.6016 -146.8882 90)
		(property "Reference" "R190"
			(at 0 0 90)
			(layer "F.SilkS")
			(hide yes)
			(effects
				(font
					(size 1.27 1.27)
				)
			)
		)
		(property "Value" "499R2F-2-GP"
			(at 0.064008 -3.993896 90)
			(unlocked yes)
			(layer "F.Fab")
			(hide yes)
			(effects
				(font
					(size 1.016 1.016)
					(thickness 0.1524)
				)
			)
		)
		(property "Device Type" "R402H16"
			(at 0.064008 -5.517896 90)
			(unlocked yes)
			(layer "F.Fab")
			(hide yes)
			(effects
				(font
					(size 1.016 1.016)
					(thickness 0.1524)
				)
			)
		)
		(duplicate_pad_numbers_are_jumpers no)
		(fp_line
			(start 0.508 -0.9398)
			(end -0.508 -0.9398)
			(stroke
				(width 0.1524)
				(type default)
			)
			(layer "F.SilkS")
		)
		(fp_line
			(start -0.508 -0.9398)
			(end -0.508 0.9398)
			(stroke
				(width 0.1524)
				(type default)
			)
			(layer "F.SilkS")
		)
		(fp_rect
			(start -0.508 0.9398)
			(end 0.508 -0.9398)
			(stroke
				(width 0)
				(type default)
			)
			(fill no)
			(layer "F.CrtYd")
		)
		(fp_rect
			(start -0.508 0.9398)
			(end 0.508 -0.9398)
			(stroke
				(width 0)
				(type default)
			)
			(fill no)
			(layer "F.Fab")
		)
		(pad "1" smd custom
			(at 0 -0.4445 90)
			(size 0.1397 0.1397)
			(layers "F.Cu" "F.Mask" "F.Paste")
			(net "I2C_BMC_COMP_SDA_OUT")
			(options
				(clearance outline)
				(anchor circle)
			)
			(primitives
				(gr_poly
					(pts
						(arc
							(start -0.1778 -0.2794)
							(mid -0.249642 -0.249642)
							(end -0.2794 -0.1778)
						)
						(arc
							(start -0.2794 0.1778)
							(mid -0.249642 0.249642)
							(end -0.1778 0.2794)
						)
						(arc
							(start 0.1778 0.2794)
							(mid 0.249642 0.249642)
							(end 0.2794 0.1778)
						)
						(arc
							(start 0.2794 -0.1778)
							(mid 0.249642 -0.249642)
							(end 0.1778 -0.2794)
						)
					)
					(width 0)
					(fill yes)
				)
			)
		)
		(pad "2" smd custom
			(at 0 0.4445 90)
			(size 0.1397 0.1397)
			(layers "F.Cu" "F.Mask" "F.Paste")
			(net "P3V3_STBY")
			(options
				(clearance outline)
				(anchor circle)
			)
			(primitives
				(gr_poly
					(pts
						(arc
							(start -0.1778 -0.2794)
							(mid -0.249642 -0.249642)
							(end -0.2794 -0.1778)
						)
						(arc
							(start -0.2794 0.1778)
							(mid -0.249642 0.249642)
							(end -0.1778 0.2794)
						)
						(arc
							(start 0.1778 0.2794)
							(mid 0.249642 0.249642)
							(end 0.2794 0.1778)
						)
						(arc
							(start 0.2794 -0.1778)
							(mid 0.249642 -0.249642)
							(end 0.1778 -0.2794)
						)
					)
					(width 0)
					(fill yes)
				)
			)
		)
	)
	(footprint ""
		(layer "F.Cu")
		(at 83.82 -147.674076 90)
		(property "Reference" "C135"
			(at 0 0 90)
			(layer "F.SilkS")
			(hide yes)
			(effects
				(font
					(size 1.27 1.27)
				)
			)
		)
		(property "Value" "SCD1U16V2KX-3GP"
			(at 1.1811 -2.7051 90)
			(unlocked yes)
			(layer "F.Fab")
			(hide yes)
			(effects
				(font
					(size 1.016 1.016)
					(thickness 0.1524)
				)
			)
		)
		(property "Device Type" "C402H22"
			(at 1.1811 -4.2291 90)
			(unlocked yes)
			(layer "F.Fab")
			(hide yes)
			(effects
				(font
					(size 1.016 1.016)
					(thickness 0.1524)
				)
			)
		)
		(duplicate_pad_numbers_are_jumpers no)
		(fp_rect
			(start -0.4318 0.9525)
			(end 0.4318 -0.9525)
			(stroke
				(width 0)
				(type default)
			)
			(fill no)
			(layer "F.CrtYd")
		)
		(fp_rect
			(start -0.4318 0.9525)
			(end 0.4318 -0.9525)
			(stroke
				(width 0)
				(type default)
			)
			(fill no)
			(layer "F.Fab")
		)
		(pad "1" smd custom
			(at 0 -0.4445 90)
			(size 0.1524 0.1524)
			(layers "F.Cu" "F.Mask" "F.Paste")
			(net "P3V3_STBY")
			(options
				(clearance outline)
				(anchor circle)
			)
			(primitives
				(gr_poly
					(pts
						(arc
							(start 0.3048 -0.2032)
							(mid 0.275042 -0.275042)
							(end 0.2032 -0.3048)
						)
						(arc
							(start -0.2032 -0.3048)
							(mid -0.275042 -0.275042)
							(end -0.3048 -0.2032)
						)
						(arc
							(start -0.3048 0.2032)
							(mid -0.275042 0.275042)
							(end -0.2032 0.3048)
						)
						(arc
							(start 0.2032 0.3048)
							(mid 0.275042 0.275042)
							(end 0.3048 0.2032)
						)
					)
					(width 0)
					(fill yes)
				)
			)
		)
		(pad "2" smd custom
			(at 0 0.4445 90)
			(size 0.1524 0.1524)
			(layers "F.Cu" "F.Mask" "F.Paste")
			(net "GND")
			(options
				(clearance outline)
				(anchor circle)
			)
			(primitives
				(gr_poly
					(pts
						(arc
							(start 0.3048 -0.2032)
							(mid 0.275042 -0.275042)
							(end 0.2032 -0.3048)
						)
						(arc
							(start -0.2032 -0.3048)
							(mid -0.275042 -0.275042)
							(end -0.3048 -0.2032)
						)
						(arc
							(start -0.3048 0.2032)
							(mid -0.275042 0.275042)
							(end -0.2032 0.3048)
						)
						(arc
							(start 0.2032 0.3048)
							(mid 0.275042 0.275042)
							(end 0.3048 0.2032)
						)
					)
					(width 0)
					(fill yes)
				)
			)
		)
	)
	(footprint ""
		(layer "F.Cu")
		(at 228.470714 -102.168706 180)
		(property "Reference" "C636"
			(at 0 0 180)
			(layer "F.SilkS")
			(hide yes)
			(effects
				(font
					(size 1.27 1.27)
				)
			)
		)
		(property "Value" "SC10U16V5KX-7-GP-U"
			(at -0.076454 -6.1214 180)
			(unlocked yes)
			(layer "F.Fab")
			(hide yes)
			(effects
				(font
					(size 1.016 1.016)
					(thickness 0.1524)
				)
			)
		)
		(property "Device Type" "C805H58"
			(at -0.076454 -8.153654 180)
			(unlocked yes)
			(layer "F.Fab")
			(hide yes)
			(effects
				(font
					(size 1.016 1.016)
					(thickness 0.1524)
				)
			)
		)
		(duplicate_pad_numbers_are_jumpers no)
		(fp_line
			(start 0.635 0)
			(end -0.635 0)
			(stroke
				(width 0.508)
				(type default)
			)
			(layer "F.SilkS")
		)
		(fp_rect
			(start -0.9652 1.778)
			(end 0.9652 -1.778)
			(stroke
				(width 0)
				(type default)
			)
			(fill no)
			(layer "F.CrtYd")
		)
		(fp_poly
			(pts
				(xy -0.9652 -1.778254) (xy 0.9652 -1.778254) (xy 0.9652 1.778) (xy -0.9652 1.778)
			)
			(stroke
				(width 0)
				(type default)
			)
			(fill no)
			(layer "F.Fab")
		)
		(pad "1" smd rect
			(at 0 -0.9652 180)
			(size 1.397 1.143)
			(layers "F.Cu" "F.Mask" "F.Paste")
			(net "P12V_STBY_VIN_U81")
		)
		(pad "2" smd rect
			(at 0 0.9652 180)
			(size 1.397 1.143)
			(layers "F.Cu" "F.Mask" "F.Paste")
			(net "GND")
		)
	)
	(footprint ""
		(layer "F.Cu")
		(at 88.813894 -62.739016 -90)
		(property "Reference" "R7"
			(at 0 0 270)
			(layer "F.SilkS")
			(hide yes)
			(effects
				(font
					(size 1.27 1.27)
				)
			)
		)
		(property "Value" "0R2J-2-GP"
			(at 0.064008 -3.993896 270)
			(unlocked yes)
			(layer "F.Fab")
			(hide yes)
			(effects
				(font
					(size 1.016 1.016)
					(thickness 0.1524)
				)
			)
		)
		(property "Device Type" "R402H16"
			(at 0.064008 -5.517896 270)
			(unlocked yes)
			(layer "F.Fab")
			(hide yes)
			(effects
				(font
					(size 1.016 1.016)
					(thickness 0.1524)
				)
			)
		)
		(duplicate_pad_numbers_are_jumpers no)
		(fp_line
			(start -0.508 -0.9398)
			(end -0.508 0.9398)
			(stroke
				(width 0.1524)
				(type default)
			)
			(layer "F.SilkS")
		)
		(fp_line
			(start 0.508 -0.9398)
			(end -0.508 -0.9398)
			(stroke
				(width 0.1524)
				(type default)
			)
			(layer "F.SilkS")
		)
		(fp_rect
			(start -0.508 0.9398)
			(end 0.508 -0.9398)
			(stroke
				(width 0)
				(type default)
			)
			(fill no)
			(layer "F.CrtYd")
		)
		(fp_rect
			(start -0.508 0.9398)
			(end 0.508 -0.9398)
			(stroke
				(width 0)
				(type default)
			)
			(fill no)
			(layer "F.Fab")
		)
		(pad "1" smd custom
			(at 0 -0.4445 270)
			(size 0.1397 0.1397)
			(layers "F.Cu" "F.Mask" "F.Paste")
			(net "NCSI_TXEN")
			(options
				(clearance outline)
				(anchor circle)
			)
			(primitives
				(gr_poly
					(pts
						(arc
							(start -0.1778 -0.2794)
							(mid -0.249642 -0.249642)
							(end -0.2794 -0.1778)
						)
						(arc
							(start -0.2794 0.1778)
							(mid -0.249642 0.249642)
							(end -0.1778 0.2794)
						)
						(arc
							(start 0.1778 0.2794)
							(mid 0.249642 0.249642)
							(end 0.2794 0.1778)
						)
						(arc
							(start 0.2794 -0.1778)
							(mid 0.249642 -0.249642)
							(end 0.1778 -0.2794)
						)
					)
					(width 0)
					(fill yes)
				)
			)
		)
		(pad "2" smd custom
			(at 0 0.4445 270)
			(size 0.1397 0.1397)
			(layers "F.Cu" "F.Mask" "F.Paste")
			(net "NCSI_TXEN_R")
			(options
				(clearance outline)
				(anchor circle)
			)
			(primitives
				(gr_poly
					(pts
						(arc
							(start -0.1778 -0.2794)
							(mid -0.249642 -0.249642)
							(end -0.2794 -0.1778)
						)
						(arc
							(start -0.2794 0.1778)
							(mid -0.249642 0.249642)
							(end -0.1778 0.2794)
						)
						(arc
							(start 0.1778 0.2794)
							(mid 0.249642 0.249642)
							(end 0.2794 0.1778)
						)
						(arc
							(start 0.2794 -0.1778)
							(mid 0.249642 -0.249642)
							(end 0.1778 -0.2794)
						)
					)
					(width 0)
					(fill yes)
				)
			)
		)
	)
	(footprint ""
		(layer "F.Cu")
		(at 149.008338 -14.987778)
		(property "Reference" "C206"
			(at 0 0 0)
			(layer "F.SilkS")
			(hide yes)
			(effects
				(font
					(size 1.27 1.27)
				)
			)
		)
		(property "Value" "SC100P50V2JN-3GP"
			(at 1.1811 -2.7051 0)
			(unlocked yes)
			(layer "F.Fab")
			(hide yes)
			(effects
				(font
					(size 1.016 1.016)
					(thickness 0.1524)
				)
			)
		)
		(property "Device Type" "C402H22"
			(at 1.1811 -4.2291 0)
			(unlocked yes)
			(layer "F.Fab")
			(hide yes)
			(effects
				(font
					(size 1.016 1.016)
					(thickness 0.1524)
				)
			)
		)
		(duplicate_pad_numbers_are_jumpers no)
		(fp_rect
			(start -0.4318 0.9525)
			(end 0.4318 -0.9525)
			(stroke
				(width 0)
				(type default)
			)
			(fill no)
			(layer "F.CrtYd")
		)
		(fp_rect
			(start -0.4318 0.9525)
			(end 0.4318 -0.9525)
			(stroke
				(width 0)
				(type default)
			)
			(fill no)
			(layer "F.Fab")
		)
		(pad "1" smd custom
			(at 0 -0.4445)
			(size 0.1524 0.1524)
			(layers "F.Cu" "F.Mask" "F.Paste")
			(net "P1V8_STBY_CC_R")
			(options
				(clearance outline)
				(anchor circle)
			)
			(primitives
				(gr_poly
					(pts
						(arc
							(start 0.3048 -0.2032)
							(mid 0.275042 -0.275042)
							(end 0.2032 -0.3048)
						)
						(arc
							(start -0.2032 -0.3048)
							(mid -0.275042 -0.275042)
							(end -0.3048 -0.2032)
						)
						(arc
							(start -0.3048 0.2032)
							(mid -0.275042 0.275042)
							(end -0.2032 0.3048)
						)
						(arc
							(start 0.2032 0.3048)
							(mid 0.275042 0.275042)
							(end 0.3048 0.2032)
						)
					)
					(width 0)
					(fill yes)
				)
			)
		)
		(pad "2" smd custom
			(at 0 0.4445)
			(size 0.1524 0.1524)
			(layers "F.Cu" "F.Mask" "F.Paste")
			(net "P1V8_STBY_VFB")
			(options
				(clearance outline)
				(anchor circle)
			)
			(primitives
				(gr_poly
					(pts
						(arc
							(start 0.3048 -0.2032)
							(mid 0.275042 -0.275042)
							(end 0.2032 -0.3048)
						)
						(arc
							(start -0.2032 -0.3048)
							(mid -0.275042 -0.275042)
							(end -0.3048 -0.2032)
						)
						(arc
							(start -0.3048 0.2032)
							(mid -0.275042 0.275042)
							(end -0.2032 0.3048)
						)
						(arc
							(start 0.2032 0.3048)
							(mid 0.275042 0.275042)
							(end 0.3048 0.2032)
						)
					)
					(width 0)
					(fill yes)
				)
			)
		)
	)
	(footprint ""
		(layer "F.Cu")
		(at 93.8276 -29.8958)
		(property "Reference" "C1"
			(at 0 0 0)
			(layer "F.SilkS")
			(hide yes)
			(effects
				(font
					(size 1.27 1.27)
				)
			)
		)
		(property "Value" "SCD1U16V2KX-3GP"
			(at 1.1811 -2.7051 0)
			(unlocked yes)
			(layer "F.Fab")
			(hide yes)
			(effects
				(font
					(size 1.016 1.016)
					(thickness 0.1524)
				)
			)
		)
		(property "Device Type" "C402H22"
			(at 1.1811 -4.2291 0)
			(unlocked yes)
			(layer "F.Fab")
			(hide yes)
			(effects
				(font
					(size 1.016 1.016)
					(thickness 0.1524)
				)
			)
		)
		(duplicate_pad_numbers_are_jumpers no)
		(fp_rect
			(start -0.4318 0.9525)
			(end 0.4318 -0.9525)
			(stroke
				(width 0)
				(type default)
			)
			(fill no)
			(layer "F.CrtYd")
		)
		(fp_rect
			(start -0.4318 0.9525)
			(end 0.4318 -0.9525)
			(stroke
				(width 0)
				(type default)
			)
			(fill no)
			(layer "F.Fab")
		)
		(pad "1" smd custom
			(at 0 -0.4445)
			(size 0.1524 0.1524)
			(layers "F.Cu" "F.Mask" "F.Paste")
			(net "P5V_STBY")
			(options
				(clearance outline)
				(anchor circle)
			)
			(primitives
				(gr_poly
					(pts
						(arc
							(start 0.3048 -0.2032)
							(mid 0.275042 -0.275042)
							(end 0.2032 -0.3048)
						)
						(arc
							(start -0.2032 -0.3048)
							(mid -0.275042 -0.275042)
							(end -0.3048 -0.2032)
						)
						(arc
							(start -0.3048 0.2032)
							(mid -0.275042 0.275042)
							(end -0.2032 0.3048)
						)
						(arc
							(start 0.2032 0.3048)
							(mid 0.275042 0.275042)
							(end 0.3048 0.2032)
						)
					)
					(width 0)
					(fill yes)
				)
			)
		)
		(pad "2" smd custom
			(at 0 0.4445)
			(size 0.1524 0.1524)
			(layers "F.Cu" "F.Mask" "F.Paste")
			(net "GND")
			(options
				(clearance outline)
				(anchor circle)
			)
			(primitives
				(gr_poly
					(pts
						(arc
							(start 0.3048 -0.2032)
							(mid 0.275042 -0.275042)
							(end 0.2032 -0.3048)
						)
						(arc
							(start -0.2032 -0.3048)
							(mid -0.275042 -0.275042)
							(end -0.3048 -0.2032)
						)
						(arc
							(start -0.3048 0.2032)
							(mid -0.275042 0.275042)
							(end -0.2032 0.3048)
						)
						(arc
							(start 0.2032 0.3048)
							(mid 0.275042 0.275042)
							(end 0.3048 0.2032)
						)
					)
					(width 0)
					(fill yes)
				)
			)
		)
	)
)
